# T6G (Grand Teton) — schematic netlist excerpt (pin names and nets, part order shuffled) for the footprints in the layout excerpt that follows; sources: Cadence DE-HDL packaged netlist, KiCad conversion of 04192023_DAF0TMB3IC0_F0TG_MB_C_brd_V02_OCP.brd

C1576  Q_CAP_DIFFBUS  DIFF BUS_0.22UF 6.3V 20% X6S  pkg C0201  page 65 : \1\ = P5E_CPU0_G3_TX_C_DN<1> ; \2\ = P5E_CPU0_G3_TX_DN<1>
R1332  Q_RES  0 5% EMPTY  pkg 0402LF  page 159 : A = I3C_SPD_DDRGL_CPU0_BYPASS_SCL ; B = I3C_SPD_DDRGL_CPU0_SCL

R1837  Q_RES_4P_12  0.001 1% CHIP  pkg R2512_4P_H41  page 259
  \1\  = P12V_AUX
  \2\  = P12V_MEM_CPU1
  \3\  = TP_P12V_AUX_CPU1_DIMM_ISEN_P
  \4\  = TP_P12V_AUX_CPU1_DIMM_ISEN_N

H87  HOLE  EMPTY  pkg TH  page 230 : \1\ = GND
TP16  TP  NA  pkg TP  page 54 : TP = VSENSE_PVDDCR_CPU1_P1_DP

(kicad_pcb
	(version 20260206)
	(generator "pcbnew")
	(generator_version "10.0")
	(general
		(thickness 1.6)
		(legacy_teardrops no)
	)
	(paper "A4")
	(title_block
		(title "04192023_DAF0TMB3IC0_F0TG_MB_C_brd_V02_OCP.brd")
		(comment 1 "Grand Teton / footprints 209-213 of 8354")
	)
	(layers
		(0 "F.Cu" signal "TOP")
		(4 "In1.Cu" signal "GND")
		(6 "In2.Cu" signal "IN1")
		(8 "In3.Cu" signal "GND1")
		(10 "In4.Cu" signal "IN2")
		(12 "In5.Cu" signal "GND2")
		(14 "In6.Cu" signal "IN3")
		(16 "In7.Cu" signal "GND3")
		(18 "In8.Cu" signal "VCC")
		(20 "In9.Cu" signal "VCC1")
		(22 "In10.Cu" signal "GND4")
		(24 "In11.Cu" signal "IN4")
		(26 "In12.Cu" signal "GND5")
		(28 "In13.Cu" signal "IN5")
		(30 "In14.Cu" signal "GND6")
		(32 "In15.Cu" signal "IN6")
		(34 "In16.Cu" signal "GND7")
		(2 "B.Cu" signal "BOTTOM")
		(9 "F.Adhes" user "F.Adhesive")
		(11 "B.Adhes" user "B.Adhesive")
		(13 "F.Paste" user "Package Geometry/Pastemask Top")
		(15 "B.Paste" user "Package Geometry/Pastemask Bottom")
		(5 "F.SilkS" user "Ref Des/Silkscreen Top")
		(7 "B.SilkS" user "Ref Des/Silkscreen Bottom")
		(1 "F.Mask" user "Board Geometry/Soldermask Top")
		(3 "B.Mask" user "Board Geometry/Soldermask Bottom")
		(17 "Dwgs.User" user "User.Drawings")
		(19 "Cmts.User" user "User.Comments")
		(21 "Eco1.User" user "User.Eco1")
		(23 "Eco2.User" user "User.Eco2")
		(25 "Edge.Cuts" user "Board Geometry/Outline")
		(27 "Margin" user)
		(31 "F.CrtYd" user "Package Geometry/Place Bound Top")
		(29 "B.CrtYd" user "Package Geometry/Place Bound Bottom")
		(35 "F.Fab" user "Ref Des/Assembly Top")
		(33 "B.Fab" user "Ref Des/Assembly Bottom")
	)
	(footprint ""
		(layer "F.Cu")
		(at 435.102 -165.9509 90)
		(property "Reference" "R1332"
			(at 0 0 90)
			(layer "F.SilkS")
			(hide yes)
			(effects
				(font
					(size 1.27 1.27)
				)
			)
		)
		(property "Value" ""
			(at 0 0 90)
			(layer "F.Fab")
			(effects
				(font
					(size 1.27 1.27)
				)
			)
		)
		(duplicate_pad_numbers_are_jumpers no)
		(fp_line
			(start 0.7874 -0.4064)
			(end 0.7874 0.4064)
			(stroke
				(width 0.1524)
				(type default)
			)
			(layer "F.SilkS")
		)
		(fp_line
			(start -0.7874 -0.4064)
			(end 0.7874 -0.4064)
			(stroke
				(width 0.1524)
				(type default)
			)
			(layer "F.SilkS")
		)
		(fp_line
			(start 0.7874 0.4064)
			(end -0.7874 0.4064)
			(stroke
				(width 0.1524)
				(type default)
			)
			(layer "F.SilkS")
		)
		(fp_line
			(start -0.7874 0.4064)
			(end -0.7874 -0.4064)
			(stroke
				(width 0.1524)
				(type default)
			)
			(layer "F.SilkS")
		)
		(fp_line
			(start -0.12065 -0.305054)
			(end -0.12065 -0.2794)
			(stroke
				(width 0.1)
				(type default)
			)
			(layer "F.Fab")
		)
		(fp_line
			(start -0.67945 -0.305054)
			(end -0.12065 -0.305054)
			(stroke
				(width 0.1)
				(type default)
			)
			(layer "F.Fab")
		)
		(fp_line
			(start 0.67945 -0.3048)
			(end 0.67945 0.3048)
			(stroke
				(width 0.1)
				(type default)
			)
			(layer "F.Fab")
		)
		(fp_line
			(start 0.12065 -0.3048)
			(end 0.67945 -0.3048)
			(stroke
				(width 0.1)
				(type default)
			)
			(layer "F.Fab")
		)
		(fp_line
			(start 0.12065 -0.2794)
			(end 0.12065 -0.3048)
			(stroke
				(width 0.1)
				(type default)
			)
			(layer "F.Fab")
		)
		(fp_line
			(start -0.12065 -0.2794)
			(end 0.12065 -0.2794)
			(stroke
				(width 0.1)
				(type default)
			)
			(layer "F.Fab")
		)
		(fp_line
			(start 0.120396 0.2794)
			(end -0.12065 0.2794)
			(stroke
				(width 0.1)
				(type default)
			)
			(layer "F.Fab")
		)
		(fp_line
			(start -0.12065 0.2794)
			(end -0.12065 0.3048)
			(stroke
				(width 0.1)
				(type default)
			)
			(layer "F.Fab")
		)
		(fp_line
			(start 0.67945 0.3048)
			(end 0.120396 0.3048)
			(stroke
				(width 0.1)
				(type default)
			)
			(layer "F.Fab")
		)
		(fp_line
			(start 0.120396 0.3048)
			(end 0.120396 0.2794)
			(stroke
				(width 0.1)
				(type default)
			)
			(layer "F.Fab")
		)
		(fp_line
			(start -0.12065 0.3048)
			(end -0.67945 0.3048)
			(stroke
				(width 0.1)
				(type default)
			)
			(layer "F.Fab")
		)
		(fp_line
			(start -0.67945 0.3048)
			(end -0.67945 -0.305054)
			(stroke
				(width 0.1)
				(type default)
			)
			(layer "F.Fab")
		)
		(pad "1" smd rect
			(at -0.40005 0 270)
			(size 0.4572 0.508)
			(layers "F.Cu" "F.Mask" "F.Paste")
			(net "I3C_SPD_DDRGL_CPU0_BYPASS_SCL")
		)
		(pad "2" smd rect
			(at 0.40005 0 270)
			(size 0.4572 0.508)
			(layers "F.Cu" "F.Mask" "F.Paste")
			(net "I3C_SPD_DDRGL_CPU0_SCL")
		)
	)
	(footprint ""
		(layer "F.Cu")
		(at 12.896342 -194.36715 -90)
		(property "Reference" "R1837"
			(at -4.2799 1.094232 90)
			(unlocked yes)
			(layer "F.SilkS")
			(effects
				(font
					(size 0.7874 0.5842)
					(thickness 0.1524)
				)
				(justify left)
			)
		)
		(property "Value" ""
			(at 0 0 270)
			(layer "F.Fab")
			(effects
				(font
					(size 1.27 1.27)
				)
			)
		)
		(duplicate_pad_numbers_are_jumpers no)
		(fp_line
			(start -4.0386 1.7526)
			(end -4.0386 -1.7526)
			(stroke
				(width 0.1524)
				(type default)
			)
			(layer "F.SilkS")
		)
		(fp_line
			(start 4.0386 1.7526)
			(end -4.0386 1.7526)
			(stroke
				(width 0.1524)
				(type default)
			)
			(layer "F.SilkS")
		)
		(fp_line
			(start -4.0386 -1.7526)
			(end 4.0386 -1.7526)
			(stroke
				(width 0.1524)
				(type default)
			)
			(layer "F.SilkS")
		)
		(fp_line
			(start 4.0386 -1.7526)
			(end 4.0386 1.7526)
			(stroke
				(width 0.1524)
				(type default)
			)
			(layer "F.SilkS")
		)
		(fp_line
			(start -4.0386 1.7526)
			(end -4.0386 -1.7526)
			(stroke
				(width 0.1)
				(type default)
			)
			(layer "F.Fab")
		)
		(fp_line
			(start 4.0386 1.7526)
			(end -4.0386 1.7526)
			(stroke
				(width 0.1)
				(type default)
			)
			(layer "F.Fab")
		)
		(fp_line
			(start -4.0386 -1.7526)
			(end 4.0386 -1.7526)
			(stroke
				(width 0.1)
				(type default)
			)
			(layer "F.Fab")
		)
		(fp_line
			(start 4.0386 -1.7526)
			(end 4.0386 1.7526)
			(stroke
				(width 0.1)
				(type default)
			)
			(layer "F.Fab")
		)
		(pad "1" smd circle
			(at -3.700018 0 180)
			(size 0 0)
			(layers "F.Cu" "F.Mask" "F.Paste")
			(net "P12V_AUX")
		)
		(pad "2" smd circle
			(at 3.700018 0)
			(size 0 0)
			(layers "F.Cu" "F.Mask" "F.Paste")
			(net "P12V_MEM_CPU1")
		)
		(pad "3" smd rect
			(at -2.70002 0)
			(size 0.4064 1.1176)
			(layers "F.Cu" "F.Mask" "F.Paste")
			(net "TP_P12V_AUX_CPU1_DIMM_ISEN_P")
		)
		(pad "4" smd rect
			(at 2.70002 0)
			(size 0.4064 1.1176)
			(layers "F.Cu" "F.Mask" "F.Paste")
			(net "TP_P12V_AUX_CPU1_DIMM_ISEN_N")
		)
	)
	(footprint ""
		(layer "F.Cu")
		(at 380.899924 -22.29993)
		(property "Reference" "H87"
			(at -5.041392 -5.687568 0)
			(unlocked yes)
			(layer "F.SilkS")
			(effects
				(font
					(size 0.7874 0.5842)
					(thickness 0.1524)
				)
				(justify left)
			)
		)
		(property "Value" ""
			(at 0 0 0)
			(layer "F.Fab")
			(effects
				(font
					(size 1.27 1.27)
				)
			)
		)
		(duplicate_pad_numbers_are_jumpers no)
		(pad "1" thru_hole circle
			(at 0 0)
			(size 10.0076 10.0076)
			(drill 5.6134)
			(layers "*.Cu" "*.Mask")
			(remove_unused_layers no)
			(net "GND")
			(clearance -1.9431)
		)
	)
	(footprint ""
		(layer "F.Cu")
		(at 429.4632 -16.100298 90)
		(property "Reference" "C1576"
			(at 0 0 90)
			(layer "F.SilkS")
			(hide yes)
			(effects
				(font
					(size 1.27 1.27)
				)
			)
		)
		(property "Value" ""
			(at 0 0 90)
			(layer "F.Fab")
			(effects
				(font
					(size 1.27 1.27)
				)
			)
		)
		(duplicate_pad_numbers_are_jumpers no)
		(fp_line
			(start 0.299974 -0.150114)
			(end 0.299974 0.150114)
			(stroke
				(width 0.1)
				(type default)
			)
			(layer "F.Fab")
		)
		(fp_line
			(start -0.299974 -0.150114)
			(end 0.299974 -0.150114)
			(stroke
				(width 0.1)
				(type default)
			)
			(layer "F.Fab")
		)
		(fp_line
			(start 0.299974 0.150114)
			(end -0.299974 0.150114)
			(stroke
				(width 0.1)
				(type default)
			)
			(layer "F.Fab")
		)
		(fp_line
			(start -0.299974 0.150114)
			(end -0.299974 -0.150114)
			(stroke
				(width 0.1)
				(type default)
			)
			(layer "F.Fab")
		)
		(pad "1" smd rect
			(at -0.2667 0 90)
			(size 0.3048 0.381)
			(layers "F.Cu" "F.Mask" "F.Paste")
			(net "P5E_CPU0_G3_TX_C_DN<1>")
		)
		(pad "2" smd rect
			(at 0.2667 0 90)
			(size 0.3048 0.381)
			(layers "F.Cu" "F.Mask" "F.Paste")
			(net "P5E_CPU0_G3_TX_DN<1>")
		)
	)
	(footprint ""
		(layer "F.Cu")
		(at 110.63732 -325.116444 180)
		(property "Reference" "TP16"
			(at -0.91948 -0.099314 0)
			(unlocked yes)
			(layer "F.SilkS")
			(effects
				(font
					(size 0.7874 0.5842)
					(thickness 0.1524)
				)
				(justify left)
			)
		)
		(property "Value" ""
			(at 0 0 180)
			(layer "F.Fab")
			(effects
				(font
					(size 1.27 1.27)
				)
			)
		)
		(duplicate_pad_numbers_are_jumpers no)
		(pad "1" smd circle
			(at 0 0 180)
			(size 0.762 0.762)
			(layers "F.Cu" "F.Mask" "F.Paste")
			(net "VSENSE_PVDDCR_CPU1_P1_DP")
		)
	)
)
